(kicad_pcb
	(version 20221018)
	(generator pcbnew)
	(general
    (thickness 1.7403)
  )
	(paper "A4")
	(title_block
    (title "Data Center RDIMM DDR4 Tester")
    (date "2024-09-30")
    (rev "1.2.4")
		(comment 9 "footprints 590-598 of 690")
	)
	(layers
    (0 "F.Cu" signal)
    (1 "In1.Cu" power)
    (2 "In2.Cu" signal)
    (3 "In3.Cu" power)
    (4 "In4.Cu" power)
    (5 "In5.Cu" signal)
    (6 "In6.Cu" power)
    (7 "In7.Cu" signal)
    (8 "In8.Cu" power)
    (9 "In9.Cu" signal)
    (10 "In10.Cu" power)
    (31 "B.Cu" signal)
    (32 "B.Adhes" user "B.Adhesive")
    (33 "F.Adhes" user "F.Adhesive")
    (34 "B.Paste" user)
    (35 "F.Paste" user)
    (36 "B.SilkS" user "B.Silkscreen")
    (37 "F.SilkS" user "F.Silkscreen")
    (38 "B.Mask" user)
    (39 "F.Mask" user)
    (40 "Dwgs.User" user "User.Drawings")
    (41 "Cmts.User" user "User.Comments")
    (42 "Eco1.User" user "User.Eco1")
    (43 "Eco2.User" user "User.Eco2")
    (44 "Edge.Cuts" user)
    (45 "Margin" user)
    (46 "B.CrtYd" user "B.Courtyard")
    (47 "F.CrtYd" user "F.Courtyard")
    (48 "B.Fab" user)
    (49 "F.Fab" user)
  )
	(footprint "data-center-rdimm-ddr4-tester-footprints:DFN3538" (layer "B.Cu")
    (at 177.21 119.7 90)
    (property "Author" "Antmicro")
    (property "License" "Apache-2.0")
    (property "MPN" "CD-MMBL110S")
    (property "Manufacturer" "Bourns")
    (property "Sheetfile" "ethernet.kicad_sch")
    (property "Sheetname" "Ethernet")
    (property "ki_description" "Bridge Rectifiers 1000V 1A MMBL DFN3538")
    (attr smd)
    (fp_text reference "D13" (at 2.27 1.07 unlocked) (layer "B.SilkS")
        (effects (font (size 0.7 0.7) (thickness 0.15)) (justify left bottom mirror))
    )
    (fp_text value "CD-MMBL110S" (at 0 -3.5 270 unlocked) (layer "B.Fab") hide
        (effects (font (size 0.7 0.7) (thickness 0.15)) (justify left bottom mirror))
    )
    (fp_text user "~" (at -0.31 -2.59 270 unlocked) (layer "B.SilkS")
        (effects (font (size 0.7 0.7) (thickness 0.15)) (justify left bottom mirror))
    )
    (fp_text user "Author: Antmicro" (at -2.1 -5.599 270) (layer "B.Fab") hide
        (effects (font (size 0.7 0.7) (thickness 0.15)) (justify left bottom mirror))
    )
    (fp_text user "${REFERENCE}" (at -2.1 -4.599 270) (layer "B.Fab") hide
        (effects (font (size 0.7 0.7) (thickness 0.15)) (justify left bottom mirror))
    )
    (fp_text user "License: Apache-2.0" (at -2.1 -6.599 270) (layer "B.Fab") hide
        (effects (font (size 0.7 0.7) (thickness 0.15)) (justify left bottom mirror))
    )
    (fp_line (start -1.8 -2.05) (end -1.6 -2.05)
      (stroke (width 0.15) (type solid)) (layer "B.SilkS"))
    (fp_line (start -1.8 1.5) (end -1.8 -2.05)
      (stroke (width 0.15) (type solid)) (layer "B.SilkS"))
    (fp_line (start -0.95 -2.05) (end 0.95 -2.05)
      (stroke (width 0.15) (type solid)) (layer "B.SilkS"))
    (fp_line (start -0.95 2) (end 0.95 2)
      (stroke (width 0.15) (type solid)) (layer "B.SilkS"))
    (fp_line (start -0.902 2.25) (end -0.6 2.25)
      (stroke (width 0.15) (type solid)) (layer "B.SilkS"))
    (fp_line (start 0.748 2.452) (end 0.748 2.15)
      (stroke (width 0.15) (type solid)) (layer "B.SilkS"))
    (fp_line (start 0.9 2.301) (end 0.598 2.301)
      (stroke (width 0.15) (type solid)) (layer "B.SilkS"))
    (fp_line (start 1.6 -2.05) (end 1.8 -2.05)
      (stroke (width 0.15) (type solid)) (layer "B.SilkS"))
    (fp_line (start 1.6 2) (end 1.8 2)
      (stroke (width 0.15) (type solid)) (layer "B.SilkS"))
    (fp_line (start 1.8 2) (end 1.8 -2.05)
      (stroke (width 0.15) (type solid)) (layer "B.SilkS"))
    (fp_rect (start -2.1 2.6) (end 2.1 -2.6)
      (stroke (width 0.05) (type solid)) (fill none) (layer "B.CrtYd"))
    (fp_line (start -1.051 2) (end -1.801 1.25)
      (stroke (width 0.15) (type solid)) (layer "B.Fab"))
    (fp_rect (start 1.8 -2.048) (end -1.8 2)
      (stroke (width 0.15) (type solid)) (fill none) (layer "B.Fab"))
    (pad "1" smd roundrect (at -1.27 1.85) (size 1.4 0.48) (layers "B.Cu" "B.Paste" "B.Mask") (roundrect_rratio 0.25)
      (net 807 "/Ethernet/VSS_RAW") (pinfunction "1") (pintype "output"))
    (pad "2" smd roundrect (at 1.27 1.85) (size 1.4 0.48) (layers "B.Cu" "B.Paste" "B.Mask") (roundrect_rratio 0.25)
      (net 808 "/Ethernet/VDD_RAW") (pinfunction "2") (pintype "output"))
    (pad "3" smd roundrect (at -1.27 -1.85) (size 1.4 0.48) (layers "B.Cu" "B.Paste" "B.Mask") (roundrect_rratio 0.25)
      (net 607 "/Ethernet/PAIR_78") (pinfunction "3") (pintype "input"))
    (pad "4" smd roundrect (at 1.27 -1.85) (size 1.4 0.48) (layers "B.Cu" "B.Paste" "B.Mask") (roundrect_rratio 0.25)
      (net 608 "/Ethernet/PAIR_910") (pinfunction "4") (pintype "input"))
  )
	(footprint "data-center-rdimm-ddr4-tester-footprints:R_0402_1005Metric" (layer "B.Cu")
    (at 241.4 82.5 180)
    (descr "Resistor SMD 0402")
    (tags "resistor SMD 0402")
    (property "Author" "Antmicro")
    (property "License" "Apache-2.0")
    (property "MPN" "CR0402-FX-3300GLF")
    (property "Manufacturer" "Bourns")
    (property "Sheetfile" "interfaces.kicad_sch")
    (property "Sheetname" "Interfaces")
    (property "Tolerance" "1%")
    (property "Val" "330R")
    (property "ki_description" "330R resistor in 0402 package with 1% tolerance")
    (attr smd)
    (fp_text reference "R187" (at -1.67 -1.31) (layer "B.SilkS")
        (effects (font (size 0.7 0.7) (thickness 0.15)) (justify left bottom mirror))
    )
    (fp_text value "R_330R_0402" (at 0 -1.4) (layer "B.Fab") hide
        (effects (font (size 0.7 0.7) (thickness 0.15)) (justify left bottom mirror))
    )
    (fp_text user "Author: Antmicro" (at -0.95 -4.169) (layer "B.Fab") hide
        (effects (font (size 0.7 0.7) (thickness 0.15)) (justify left bottom mirror))
    )
    (fp_text user "${REFERENCE}" (at -0.95 -3.168) (layer "B.Fab") hide
        (effects (font (size 0.7 0.7) (thickness 0.15)) (justify left bottom mirror))
    )
    (fp_text user "License: Apache-2.0" (at -0.95 -5.169) (layer "B.Fab") hide
        (effects (font (size 0.7 0.7) (thickness 0.15)) (justify left bottom mirror))
    )
    (fp_rect (start -0.93 0.47) (end 0.93 -0.47)
      (stroke (width 0.05) (type solid)) (fill none) (layer "B.CrtYd"))
    (fp_rect (start -0.5 0.25) (end 0.5 -0.25)
      (stroke (width 0.15) (type solid)) (fill none) (layer "B.Fab"))
    (pad "1" smd roundrect (at -0.485 0 180) (size 0.59 0.64) (layers "B.Cu" "B.Paste" "B.Mask") (roundrect_rratio 0.25)
      (net 106 "Net-(D17-C_{Y})") (pintype "passive"))
    (pad "2" smd roundrect (at 0.485 0 180) (size 0.59 0.64) (layers "B.Cu" "B.Paste" "B.Mask") (roundrect_rratio 0.25)
      (net 573 "Net-(Q1-D)") (pintype "passive"))
  )
	(footprint "data-center-rdimm-ddr4-tester-footprints:C_0402_1005Metric" (layer "B.Cu")
    (at 231.8 126.3 90)
    (descr "Capacitor SMD 0402")
    (tags "capacitor SMD 0402")
    (property "Author" "Antmicro")
    (property "Dielectric" "")
    (property "License" "Apache-2.0")
    (property "MPN" "C1005X6S1A105K050BC")
    (property "Manufacturer" "TDK")
    (property "Sheetfile" "supply.kicad_sch")
    (property "Sheetname" "Supply")
    (property "Val" "1u")
    (property "Voltage" "")
    (property "ki_description" " ")
    (attr smd)
    (fp_text reference "C281" (at 1.34 1.3 270) (layer "B.SilkS")
        (effects (font (size 0.7 0.7) (thickness 0.15)) (justify left bottom mirror))
    )
    (fp_text value "C_1u_0402" (at 0 -1.4 270) (layer "B.Fab") hide
        (effects (font (size 0.7 0.7) (thickness 0.15)) (justify left bottom mirror))
    )
    (fp_text user "${REFERENCE}" (at -0.932 -3.168 270) (layer "B.Fab") hide
        (effects (font (size 0.7 0.7) (thickness 0.15)) (justify left bottom mirror))
    )
    (fp_text user "Author: Antmicro" (at -0.932 -4.17 270) (layer "B.Fab") hide
        (effects (font (size 0.7 0.7) (thickness 0.15)) (justify left bottom mirror))
    )
    (fp_text user "License: Apache-2.0" (at -0.932 -5.17 270) (layer "B.Fab") hide
        (effects (font (size 0.7 0.7) (thickness 0.15)) (justify left bottom mirror))
    )
    (fp_rect (start -0.94 0.47) (end 0.94 -0.47)
      (stroke (width 0.05) (type solid)) (fill none) (layer "B.CrtYd"))
    (fp_rect (start -0.499 0.249) (end 0.499 -0.249)
      (stroke (width 0.15) (type solid)) (fill none) (layer "B.Fab"))
    (pad "1" smd roundrect (at -0.484 0 90) (size 0.59 0.64) (layers "B.Cu" "B.Paste" "B.Mask") (roundrect_rratio 0.25)
      (net 846 "5V_ON_OFF") (pintype "passive"))
    (pad "2" smd roundrect (at 0.484 0 90) (size 0.59 0.64) (layers "B.Cu" "B.Paste" "B.Mask") (roundrect_rratio 0.25)
      (net 9 "GND") (pintype "passive"))
  )
	(footprint "data-center-rdimm-ddr4-tester-footprints:C_0603_1608Metric" (layer "B.Cu")
    (at 182.075 98.175)
    (descr "Capacitor SMD 0603")
    (tags "capacitor 0603")
    (property "Author" "Antmicro")
    (property "Dielectric" "")
    (property "License" "Apache-2.0")
    (property "MPN" "GRM188R60J476ME15D")
    (property "Manufacturer" "Murata")
    (property "Sheetfile" "fpga-power.kicad_sch")
    (property "Sheetname" "FPGA power")
    (property "Val" "47u")
    (property "Voltage" "")
    (property "ki_description" " ")
    (attr smd)
    (fp_text reference "C78" (at 1.535 -0.555 180) (layer "B.SilkS")
        (effects (font (size 0.7 0.7) (thickness 0.15)) (justify left bottom mirror))
    )
    (fp_text value "C_47u_0603" (at 0 -1.6 180) (layer "B.Fab") hide
        (effects (font (size 0.7 0.7) (thickness 0.15)) (justify left bottom mirror))
    )
    (fp_text user "Author: Antmicro" (at -1.682 -4.894 180) (layer "B.Fab") hide
        (effects (font (size 0.7 0.7) (thickness 0.15)) (justify left bottom mirror))
    )
    (fp_text user "${REFERENCE}" (at -1.682 -3.895 180) (layer "B.Fab") hide
        (effects (font (size 0.7 0.7) (thickness 0.15)) (justify left bottom mirror))
    )
    (fp_text user "License: Apache-2.0" (at -1.682 -5.895 180) (layer "B.Fab") hide
        (effects (font (size 0.7 0.7) (thickness 0.15)) (justify left bottom mirror))
    )
    (fp_line (start -0.3 -0.3) (end 0.3 -0.3)
      (stroke (width 0.15) (type solid)) (layer "B.SilkS"))
    (fp_line (start -0.3 0.3) (end 0.3 0.3)
      (stroke (width 0.15) (type solid)) (layer "B.SilkS"))
    (fp_rect (start -1.24 0.7) (end 1.24 -0.7)
      (stroke (width 0.05) (type solid)) (fill none) (layer "B.CrtYd"))
    (fp_rect (start -0.8 0.4) (end 0.8 -0.4)
      (stroke (width 0.15) (type solid)) (fill none) (layer "B.Fab"))
    (pad "1" smd roundrect (at -0.7 0) (size 0.6 0.8) (layers "B.Cu" "B.Paste" "B.Mask") (roundrect_rratio 0.2)
      (net 143 "3V3_SYS") (pintype "passive"))
    (pad "2" smd roundrect (at 0.7 0) (size 0.6 0.8) (layers "B.Cu" "B.Paste" "B.Mask") (roundrect_rratio 0.2)
      (net 9 "GND") (pintype "passive"))
  )
	(footprint "data-center-rdimm-ddr4-tester-footprints:C_0201" (layer "B.Cu")
    (at 191.6 100.725)
    (descr "Capacitor SMD 0201")
    (tags "capacitor SMD 0201")
    (property "Author" "Antmicro")
    (property "Dielectric" "")
    (property "License" "Apache-2.0")
    (property "MPN" "CC0201KRX6S5BB104")
    (property "Manufacturer" "Yaego")
    (property "Sheetfile" "fpga-power.kicad_sch")
    (property "Sheetname" "FPGA power")
    (property "Val" "100n")
    (property "Voltage" "")
    (property "ki_description" " ")
    (attr smd)
    (fp_text reference "C241" (at 3.26 0.385 180) (layer "B.SilkS")
        (effects (font (size 0.7 0.7) (thickness 0.15)) (justify left bottom mirror))
    )
    (fp_text value "C_100n_0201" (at 0 -1.4 180) (layer "B.Fab") hide
        (effects (font (size 0.7 0.7) (thickness 0.15)) (justify left bottom mirror))
    )
    (fp_text user "Author: Antmicro" (at -0.72 -5.4 180) (layer "B.Fab") hide
        (effects (font (size 0.7 0.7) (thickness 0.15)) (justify left bottom mirror))
    )
    (fp_text user "License: Apache-2.0" (at -0.72 -4.4 180) (layer "B.Fab") hide
        (effects (font (size 0.7 0.7) (thickness 0.15)) (justify left bottom mirror))
    )
    (fp_text user "${REFERENCE}" (at -0.72 -3.4 180) (layer "B.Fab") hide
        (effects (font (size 0.7 0.7) (thickness 0.15)) (justify left bottom mirror))
    )
    (fp_rect (start -0.72 0.38) (end 0.72 -0.38)
      (stroke (width 0.05) (type solid)) (fill none) (layer "B.CrtYd"))
    (fp_rect (start 0.3 -0.15) (end -0.301 0.149)
      (stroke (width 0.15) (type solid)) (fill none) (layer "B.Fab"))
    (pad "" smd roundrect (at -0.349 0.002) (size 0.318 0.36) (layers "B.Paste") (roundrect_rratio 0.25))
    (pad "" smd roundrect (at 0.341 0.002) (size 0.318 0.36) (layers "B.Paste") (roundrect_rratio 0.25))
    (pad "1" smd roundrect (at -0.321 0.002) (size 0.46 0.4) (layers "B.Cu" "B.Mask") (roundrect_rratio 0.25)
      (net 147 "1V0_SYS") (pintype "passive"))
    (pad "2" smd roundrect (at 0.32 0.002) (size 0.46 0.4) (layers "B.Cu" "B.Mask") (roundrect_rratio 0.25)
      (net 9 "GND") (pintype "passive"))
  )
	(footprint "data-center-rdimm-ddr4-tester-footprints:C_0201" (layer "B.Cu")
    (at 192.475 93.525)
    (descr "Capacitor SMD 0201")
    (tags "capacitor SMD 0201")
    (property "Author" "Antmicro")
    (property "Dielectric" "")
    (property "License" "Apache-2.0")
    (property "MPN" "CC0201KRX6S5BB104")
    (property "Manufacturer" "Yaego")
    (property "Sheetfile" "fpga-power.kicad_sch")
    (property "Sheetname" "FPGA power")
    (property "Val" "100n")
    (property "Voltage" "")
    (property "ki_description" " ")
    (attr smd)
    (fp_text reference "C240" (at 3.355 0.495 180) (layer "B.SilkS")
        (effects (font (size 0.7 0.7) (thickness 0.15)) (justify left bottom mirror))
    )
    (fp_text value "C_100n_0201" (at 0 -1.4 180) (layer "B.Fab") hide
        (effects (font (size 0.7 0.7) (thickness 0.15)) (justify left bottom mirror))
    )
    (fp_text user "License: Apache-2.0" (at -0.72 -4.4 180) (layer "B.Fab") hide
        (effects (font (size 0.7 0.7) (thickness 0.15)) (justify left bottom mirror))
    )
    (fp_text user "${REFERENCE}" (at -0.72 -3.4 180) (layer "B.Fab") hide
        (effects (font (size 0.7 0.7) (thickness 0.15)) (justify left bottom mirror))
    )
    (fp_text user "Author: Antmicro" (at -0.72 -5.4 180) (layer "B.Fab") hide
        (effects (font (size 0.7 0.7) (thickness 0.15)) (justify left bottom mirror))
    )
    (fp_rect (start -0.72 0.38) (end 0.72 -0.38)
      (stroke (width 0.05) (type solid)) (fill none) (layer "B.CrtYd"))
    (fp_rect (start 0.3 -0.15) (end -0.301 0.149)
      (stroke (width 0.15) (type solid)) (fill none) (layer "B.Fab"))
    (pad "" smd roundrect (at -0.349 0.002) (size 0.318 0.36) (layers "B.Paste") (roundrect_rratio 0.25))
    (pad "" smd roundrect (at 0.341 0.002) (size 0.318 0.36) (layers "B.Paste") (roundrect_rratio 0.25))
    (pad "1" smd roundrect (at -0.321 0.002) (size 0.46 0.4) (layers "B.Cu" "B.Mask") (roundrect_rratio 0.25)
      (net 147 "1V0_SYS") (pintype "passive"))
    (pad "2" smd roundrect (at 0.32 0.002) (size 0.46 0.4) (layers "B.Cu" "B.Mask") (roundrect_rratio 0.25)
      (net 9 "GND") (pintype "passive"))
  )
	(footprint "data-center-rdimm-ddr4-tester-footprints:R_0603_1608Metric" (layer "B.Cu")
    (at 114.3 114.1 90)
    (descr "Resistor SMD 0603")
    (tags "resistor SMD 0603")
    (property "Author" "Antmicro")
    (property "License" "Apache-2.0")
    (property "MPN" "ERJ-UP3F3300V")
    (property "Manufacturer" "Panasonic")
    (property "Sheetfile" "supply.kicad_sch")
    (property "Sheetname" "Supply")
    (property "Tolerance" "1%")
    (property "Val" "330R")
    (property "ki_description" "330R resistor in 0603 package with 1% tolerance")
    (attr smd)
    (fp_text reference "R114" (at 1.3 1.52 270) (layer "B.SilkS")
        (effects (font (size 0.7 0.7) (thickness 0.15)) (justify left bottom mirror))
    )
    (fp_text value "R_330R_0.25W_0603" (at 0 -1.6 270) (layer "B.Fab") hide
        (effects (font (size 0.7 0.7) (thickness 0.15)) (justify left bottom mirror))
    )
    (fp_text user "License: Apache-2.0" (at -1.25 -5.9 270) (layer "B.Fab") hide
        (effects (font (size 0.7 0.7) (thickness 0.15)) (justify left bottom mirror))
    )
    (fp_text user "${REFERENCE}" (at -1.25 -3.898 270) (layer "B.Fab") hide
        (effects (font (size 0.7 0.7) (thickness 0.15)) (justify left bottom mirror))
    )
    (fp_text user "Author: Antmicro" (at -1.25 -4.9 270) (layer "B.Fab") hide
        (effects (font (size 0.7 0.7) (thickness 0.15)) (justify left bottom mirror))
    )
    (fp_line (start -0.3 -0.3) (end 0.3 -0.3)
      (stroke (width 0.15) (type solid)) (layer "B.SilkS"))
    (fp_line (start -0.3 0.3) (end 0.3 0.3)
      (stroke (width 0.15) (type solid)) (layer "B.SilkS"))
    (fp_rect (start -1.25 0.7) (end 1.25 -0.7)
      (stroke (width 0.05) (type solid)) (fill none) (layer "B.CrtYd"))
    (fp_rect (start -0.8 0.4) (end 0.8 -0.4)
      (stroke (width 0.15) (type solid)) (fill none) (layer "B.Fab"))
    (pad "1" smd roundrect (at -0.7 0 90) (size 0.6 0.8) (layers "B.Cu" "B.Paste" "B.Mask") (roundrect_rratio 0.2)
      (net 857 "Net-(R114-Pad1)") (pintype "passive"))
    (pad "2" smd roundrect (at 0.7 0 90) (size 0.6 0.8) (layers "B.Cu" "B.Paste" "B.Mask") (roundrect_rratio 0.2)
      (net 143 "3V3_SYS") (pintype "passive"))
  )
	(footprint "data-center-rdimm-ddr4-tester-footprints:R_0402_1005Metric" (layer "B.Cu")
    (at 241.4 78.4 180)
    (descr "Resistor SMD 0402")
    (tags "resistor SMD 0402")
    (property "Author" "Antmicro")
    (property "License" "Apache-2.0")
    (property "MPN" "CR0402-FX-3300GLF")
    (property "Manufacturer" "Bourns")
    (property "Sheetfile" "interfaces.kicad_sch")
    (property "Sheetname" "Interfaces")
    (property "Tolerance" "1%")
    (property "Val" "330R")
    (property "ki_description" "330R resistor in 0402 package with 1% tolerance")
    (attr smd)
    (fp_text reference "R189" (at -1.64 -1.25) (layer "B.SilkS")
        (effects (font (size 0.7 0.7) (thickness 0.15)) (justify left bottom mirror))
    )
    (fp_text value "R_330R_0402" (at 0 -1.4) (layer "B.Fab") hide
        (effects (font (size 0.7 0.7) (thickness 0.15)) (justify left bottom mirror))
    )
    (fp_text user "Author: Antmicro" (at -0.95 -4.169) (layer "B.Fab") hide
        (effects (font (size 0.7 0.7) (thickness 0.15)) (justify left bottom mirror))
    )
    (fp_text user "${REFERENCE}" (at -0.95 -3.168) (layer "B.Fab") hide
        (effects (font (size 0.7 0.7) (thickness 0.15)) (justify left bottom mirror))
    )
    (fp_text user "License: Apache-2.0" (at -0.95 -5.169) (layer "B.Fab") hide
        (effects (font (size 0.7 0.7) (thickness 0.15)) (justify left bottom mirror))
    )
    (fp_rect (start -0.93 0.47) (end 0.93 -0.47)
      (stroke (width 0.05) (type solid)) (fill none) (layer "B.CrtYd"))
    (fp_rect (start -0.5 0.25) (end 0.5 -0.25)
      (stroke (width 0.15) (type solid)) (fill none) (layer "B.Fab"))
    (pad "1" smd roundrect (at -0.485 0 180) (size 0.59 0.64) (layers "B.Cu" "B.Paste" "B.Mask") (roundrect_rratio 0.25)
      (net 101 "Net-(D17-C_{R})") (pintype "passive"))
    (pad "2" smd roundrect (at 0.485 0 180) (size 0.59 0.64) (layers "B.Cu" "B.Paste" "B.Mask") (roundrect_rratio 0.25)
      (net 582 "Net-(Q10-D)") (pintype "passive"))
  )
	(footprint "data-center-rdimm-ddr4-tester-footprints:C_0201" (layer "B.Cu")
    (at 175.225 94.075 -90)
    (descr "Capacitor SMD 0201")
    (tags "capacitor SMD 0201")
    (property "Author" "Antmicro")
    (property "Dielectric" "")
    (property "License" "Apache-2.0")
    (property "MPN" "CC0201KRX6S5BB104")
    (property "Manufacturer" "Yaego")
    (property "Sheetfile" "fpga-power.kicad_sch")
    (property "Sheetname" "FPGA power")
    (property "Val" "100n")
    (property "Voltage" "")
    (property "ki_description" " ")
    (attr smd)
    (fp_text reference "C95" (at -2.845 -0.395 90) (layer "B.SilkS")
        (effects (font (size 0.7 0.7) (thickness 0.15)) (justify left bottom mirror))
    )
    (fp_text value "C_100n_0201" (at 0 -1.4 90) (layer "B.Fab") hide
        (effects (font (size 0.7 0.7) (thickness 0.15)) (justify left bottom mirror))
    )
    (fp_text user "License: Apache-2.0" (at -0.72 -4.4 90) (layer "B.Fab") hide
        (effects (font (size 0.7 0.7) (thickness 0.15)) (justify left bottom mirror))
    )
    (fp_text user "Author: Antmicro" (at -0.72 -5.4 90) (layer "B.Fab") hide
        (effects (font (size 0.7 0.7) (thickness 0.15)) (justify left bottom mirror))
    )
    (fp_text user "${REFERENCE}" (at -0.72 -3.4 90) (layer "B.Fab") hide
        (effects (font (size 0.7 0.7) (thickness 0.15)) (justify left bottom mirror))
    )
    (fp_rect (start -0.72 0.38) (end 0.72 -0.38)
      (stroke (width 0.05) (type solid)) (fill none) (layer "B.CrtYd"))
    (fp_rect (start 0.3 -0.15) (end -0.301 0.149)
      (stroke (width 0.15) (type solid)) (fill none) (layer "B.Fab"))
    (pad "" smd roundrect (at -0.349 0.002 270) (size 0.318 0.36) (layers "B.Paste") (roundrect_rratio 0.25))
    (pad "" smd roundrect (at 0.341 0.002 270) (size 0.318 0.36) (layers "B.Paste") (roundrect_rratio 0.25))
    (pad "1" smd roundrect (at -0.321 0.002 270) (size 0.46 0.4) (layers "B.Cu" "B.Mask") (roundrect_rratio 0.25)
      (net 143 "3V3_SYS") (pintype "passive"))
    (pad "2" smd roundrect (at 0.32 0.002 270) (size 0.46 0.4) (layers "B.Cu" "B.Mask") (roundrect_rratio 0.25)
      (net 9 "GND") (pintype "passive"))
  )
)
